(kicad_pcb
	(version 20241229)
	(generator "pcbnew")
	(generator_version "9.0")
	(general
		(thickness 1.62)
		(legacy_teardrops no)
	)
	(paper "A3")
	(title_block
		(title "COM Express 7 Baseboard")
		(date "2025-02-04")
		(rev "1.1.2")
		(company "Antmicro Ltd")
		(comment 1 "www.antmicro.com")
		(comment 9 "footprints 666-670 of 802")
	)
	(layers
		(0 "F.Cu" signal)
		(4 "In1.Cu" signal)
		(6 "In2.Cu" signal)
		(8 "In3.Cu" signal)
		(10 "In4.Cu" signal)
		(12 "In5.Cu" signal)
		(14 "In6.Cu" signal)
		(2 "B.Cu" signal)
		(9 "F.Adhes" user "F.Adhesive")
		(11 "B.Adhes" user "B.Adhesive")
		(13 "F.Paste" user)
		(15 "B.Paste" user)
		(5 "F.SilkS" user "F.Silkscreen")
		(7 "B.SilkS" user "B.Silkscreen")
		(1 "F.Mask" user)
		(3 "B.Mask" user)
		(17 "Dwgs.User" user "User.Drawings")
		(19 "Cmts.User" user "User.Comments")
		(21 "Eco1.User" user "User.Eco1")
		(23 "Eco2.User" user "User.Eco2")
		(25 "Edge.Cuts" user)
		(27 "Margin" user)
		(31 "F.CrtYd" user "F.Courtyard")
		(29 "B.CrtYd" user "B.Courtyard")
		(35 "F.Fab" user)
		(33 "B.Fab" user)
	)
	(footprint "antmicro-footprints:SOT-23-3"
		(layer "B.Cu")
		(at 140.7 132.51)
		(property "Reference" "D22"
			(at -1.15 -1.75 0)
			(layer "B.SilkS")
			(effects
				(font
					(size 0.7 0.7)
					(thickness 0.15)
				)
				(justify right bottom mirror)
			)
		)
		(property "Value" "BAT54C"
			(at -1.9 -2.7 0)
			(layer "B.Fab")
			(effects
				(font
					(size 0.7 0.7)
					(thickness 0.15)
				)
				(justify right bottom mirror)
			)
		)
		(property "Datasheet" "https://diotec.com/request/datasheet/bat54.pdf"
			(at 0 0 0)
			(layer "F.Fab")
			(hide yes)
			(effects
				(font
					(size 1.27 1.27)
					(thickness 0.15)
				)
			)
		)
		(property "Author" "Antmicro"
			(at 0 0 0)
			(layer "B.Fab")
			(hide yes)
			(effects
				(font
					(size 1 1)
					(thickness 0.15)
				)
				(justify mirror)
			)
		)
		(property "License" "Apache-2.0"
			(at 0 0 0)
			(layer "B.Fab")
			(hide yes)
			(effects
				(font
					(size 1 1)
					(thickness 0.15)
				)
				(justify mirror)
			)
		)
		(property "MPN" "BAT54C"
			(at 0 0 0)
			(layer "B.Fab")
			(hide yes)
			(effects
				(font
					(size 1 1)
					(thickness 0.15)
				)
				(justify mirror)
			)
		)
		(property "Manufacturer" "Diotec Semiconductor"
			(at 0 0 0)
			(layer "B.Fab")
			(hide yes)
			(effects
				(font
					(size 1 1)
					(thickness 0.15)
				)
				(justify mirror)
			)
		)
		(sheetname "KR to SFI #1")
		(sheetfile "kr_sfi.kicad_sch")
		(attr smd)
		(fp_line
			(start -0.85 1.35)
			(end -1.45 1.35)
			(stroke
				(width 0.15)
				(type solid)
			)
			(layer "B.SilkS")
		)
		(fp_line
			(start -0.7 -1.5)
			(end 0.7 -1.5)
			(stroke
				(width 0.15)
				(type solid)
			)
			(layer "B.SilkS")
		)
		(fp_line
			(start -0.7 -1.35)
			(end -0.7 -1.5)
			(stroke
				(width 0.15)
				(type solid)
			)
			(layer "B.SilkS")
		)
		(fp_line
			(start -0.7 1.5)
			(end -0.85 1.35)
			(stroke
				(width 0.15)
				(type solid)
			)
			(layer "B.SilkS")
		)
		(fp_line
			(start -0.7 1.5)
			(end 0.7 1.5)
			(stroke
				(width 0.15)
				(type solid)
			)
			(layer "B.SilkS")
		)
		(fp_line
			(start 0.7 -1.5)
			(end 0.7 -0.4)
			(stroke
				(width 0.15)
				(type solid)
			)
			(layer "B.SilkS")
		)
		(fp_line
			(start 0.7 1.5)
			(end 0.7 0.4)
			(stroke
				(width 0.15)
				(type solid)
			)
			(layer "B.SilkS")
		)
		(fp_line
			(start -1.75 -1.4)
			(end -0.85 -1.4)
			(stroke
				(width 0.05)
				(type solid)
			)
			(layer "B.CrtYd")
		)
		(fp_line
			(start -1.75 -0.5)
			(end -1.75 -1.4)
			(stroke
				(width 0.05)
				(type solid)
			)
			(layer "B.CrtYd")
		)
		(fp_line
			(start -1.75 0.5)
			(end -0.85 0.5)
			(stroke
				(width 0.05)
				(type solid)
			)
			(layer "B.CrtYd")
		)
		(fp_line
			(start -1.75 1.4)
			(end -1.75 0.5)
			(stroke
				(width 0.05)
				(type solid)
			)
			(layer "B.CrtYd")
		)
		(fp_line
			(start -1.75 1.4)
			(end -0.9 1.4)
			(stroke
				(width 0.05)
				(type solid)
			)
			(layer "B.CrtYd")
		)
		(fp_line
			(start -0.9 1.4)
			(end -0.9 1.6)
			(stroke
				(width 0.05)
				(type solid)
			)
			(layer "B.CrtYd")
		)
		(fp_line
			(start -0.85 -1.65)
			(end 0.85 -1.65)
			(stroke
				(width 0.05)
				(type solid)
			)
			(layer "B.CrtYd")
		)
		(fp_line
			(start -0.85 -1.4)
			(end -0.85 -1.65)
			(stroke
				(width 0.05)
				(type solid)
			)
			(layer "B.CrtYd")
		)
		(fp_line
			(start -0.85 -0.5)
			(end -1.75 -0.5)
			(stroke
				(width 0.05)
				(type solid)
			)
			(layer "B.CrtYd")
		)
		(fp_line
			(start -0.85 0.5)
			(end -0.85 -0.5)
			(stroke
				(width 0.05)
				(type solid)
			)
			(layer "B.CrtYd")
		)
		(fp_line
			(start 0.825 0.45)
			(end 0.825 1.6)
			(stroke
				(width 0.05)
				(type solid)
			)
			(layer "B.CrtYd")
		)
		(fp_line
			(start 0.825 1.6)
			(end -0.9 1.6)
			(stroke
				(width 0.05)
				(type solid)
			)
			(layer "B.CrtYd")
		)
		(fp_line
			(start 0.85 -1.65)
			(end 0.85 -0.45)
			(stroke
				(width 0.05)
				(type solid)
			)
			(layer "B.CrtYd")
		)
		(fp_line
			(start 0.85 -0.45)
			(end 1.75 -0.45)
			(stroke
				(width 0.05)
				(type solid)
			)
			(layer "B.CrtYd")
		)
		(fp_line
			(start 1.75 -0.45)
			(end 1.75 0.45)
			(stroke
				(width 0.05)
				(type solid)
			)
			(layer "B.CrtYd")
		)
		(fp_line
			(start 1.75 0.45)
			(end 0.825 0.45)
			(stroke
				(width 0.05)
				(type solid)
			)
			(layer "B.CrtYd")
		)
		(fp_line
			(start -0.712 -1.523)
			(end -0.712 1.325)
			(stroke
				(width 0.15)
				(type solid)
			)
			(layer "B.Fab")
		)
		(fp_line
			(start -0.712 1.325)
			(end -0.437 1.526)
			(stroke
				(width 0.15)
				(type solid)
			)
			(layer "B.Fab")
		)
		(fp_line
			(start 0.688 -1.519)
			(end -0.712 -1.519)
			(stroke
				(width 0.15)
				(type solid)
			)
			(layer "B.Fab")
		)
		(fp_line
			(start 0.688 1.52)
			(end 0.688 -1.519)
			(stroke
				(width 0.15)
				(type solid)
			)
			(layer "B.Fab")
		)
		(fp_line
			(start 0.688 1.526)
			(end -0.437 1.526)
			(stroke
				(width 0.15)
				(type solid)
			)
			(layer "B.Fab")
		)
		(pad "1" smd roundrect
			(at -1.1 0.951)
			(size 1 0.6)
			(layers "B.Cu" "B.Mask" "B.Paste")
			(roundrect_rratio 0.15)
			(net 141 "/2xSFP+/KR to SFI #1/~{RESET}")
			(pinfunction "1")
			(pintype "passive")
			(teardrops
				(best_length_ratio 0.2)
				(max_length 1)
				(best_width_ratio 0.9)
				(max_width 2)
				(curved_edges yes)
				(filter_ratio 0.9)
				(enabled yes)
				(allow_two_segments yes)
				(prefer_zone_connections yes)
			)
		)
		(pad "2" smd roundrect
			(at -1.1 -0.949)
			(size 1 0.6)
			(layers "B.Cu" "B.Mask" "B.Paste")
			(roundrect_rratio 0.15)
			(net 141 "/2xSFP+/KR to SFI #1/~{RESET}")
			(pinfunction "2")
			(pintype "passive")
			(teardrops
				(best_length_ratio 0.2)
				(max_length 1)
				(best_width_ratio 0.9)
				(max_width 2)
				(curved_edges yes)
				(filter_ratio 0.9)
				(enabled yes)
				(allow_two_segments yes)
				(prefer_zone_connections yes)
			)
		)
		(pad "3" smd roundrect
			(at 1.1 0.0005)
			(size 1 0.6)
			(layers "B.Cu" "B.Mask" "B.Paste")
			(roundrect_rratio 0.15)
			(net 142 "/2xSFP+/PHY0_{RESET}")
			(pinfunction "3")
			(pintype "passive")
			(teardrops
				(best_length_ratio 0.2)
				(max_length 1)
				(best_width_ratio 0.9)
				(max_width 2)
				(curved_edges yes)
				(filter_ratio 0.9)
				(enabled yes)
				(allow_two_segments yes)
				(prefer_zone_connections yes)
			)
		)
	)
	(footprint "antmicro-footprints:C_0402_1005Metric"
		(layer "B.Cu")
		(at 110.85 96.46 180)
		(descr "Capacitor SMD 0402")
		(tags "capacitor SMD 0402")
		(property "Reference" "C2"
			(at -0.8 0.5 0)
			(layer "B.SilkS")
			(effects
				(font
					(size 0.7 0.7)
					(thickness 0.15)
				)
				(justify left bottom mirror)
			)
		)
		(property "Value" "C_1u_0402"
			(at -1.022927 -2.155213 0)
			(layer "B.Fab")
			(effects
				(font
					(size 0.7 0.7)
					(thickness 0.15)
				)
				(justify left bottom mirror)
			)
		)
		(property "Datasheet" "https://product.tdk.com/en/search/capacitor/ceramic/mlcc/info?part_no=C1005X6S1A105K050BC"
			(at 0 0 180)
			(layer "F.Fab")
			(hide yes)
			(effects
				(font
					(size 1.27 1.27)
					(thickness 0.15)
				)
			)
		)
		(property "Author" "Antmicro"
			(at 221.7 192.92 0)
			(layer "B.Fab")
			(hide yes)
			(effects
				(font
					(size 1 1)
					(thickness 0.15)
				)
				(justify mirror)
			)
		)
		(property "Dielectric" ""
			(at 221.7 192.92 0)
			(layer "B.Fab")
			(hide yes)
			(effects
				(font
					(size 1 1)
					(thickness 0.15)
				)
				(justify mirror)
			)
		)
		(property "License" "Apache-2.0"
			(at 221.7 192.92 0)
			(layer "B.Fab")
			(hide yes)
			(effects
				(font
					(size 1 1)
					(thickness 0.15)
				)
				(justify mirror)
			)
		)
		(property "MPN" "C1005X6S1A105K050BC"
			(at 221.7 192.92 0)
			(layer "B.Fab")
			(hide yes)
			(effects
				(font
					(size 1 1)
					(thickness 0.15)
				)
				(justify mirror)
			)
		)
		(property "Manufacturer" "TDK"
			(at 221.7 192.92 0)
			(layer "B.Fab")
			(hide yes)
			(effects
				(font
					(size 1 1)
					(thickness 0.15)
				)
				(justify mirror)
			)
		)
		(property "Public" "False"
			(at 221.7 192.92 0)
			(layer "B.Fab")
			(hide yes)
			(effects
				(font
					(size 1 1)
					(thickness 0.15)
				)
				(justify mirror)
			)
		)
		(property "Val" "1u"
			(at 221.7 192.92 0)
			(layer "B.Fab")
			(hide yes)
			(effects
				(font
					(size 1 1)
					(thickness 0.15)
				)
				(justify mirror)
			)
		)
		(property "Voltage" ""
			(at 221.7 192.92 0)
			(layer "B.Fab")
			(hide yes)
			(effects
				(font
					(size 1 1)
					(thickness 0.15)
				)
				(justify mirror)
			)
		)
		(sheetname "2xUSB3.0+RJ45")
		(sheetfile "usb3+rj45.kicad_sch")
		(attr smd)
		(fp_rect
			(start -0.925 0.47)
			(end 0.925 -0.47)
			(stroke
				(width 0.05)
				(type default)
			)
			(fill no)
			(layer "B.CrtYd")
		)
		(fp_line
			(start 0.504 0.25)
			(end -0.494 0.25)
			(stroke
				(width 0.15)
				(type solid)
			)
			(layer "B.Fab")
		)
		(fp_line
			(start 0.504 -0.248)
			(end 0.504 0.25)
			(stroke
				(width 0.15)
				(type solid)
			)
			(layer "B.Fab")
		)
		(fp_line
			(start -0.494 0.25)
			(end -0.494 -0.248)
			(stroke
				(width 0.15)
				(type solid)
			)
			(layer "B.Fab")
		)
		(fp_line
			(start -0.494 -0.248)
			(end 0.504 -0.248)
			(stroke
				(width 0.15)
				(type solid)
			)
			(layer "B.Fab")
		)
		(pad "1" smd roundrect
			(at -0.48 0 180)
			(size 0.59 0.64)
			(layers "B.Cu" "B.Mask" "B.Paste")
			(roundrect_rratio 0.25)
			(net 1 "GND")
			(pintype "passive")
			(teardrops
				(best_length_ratio 0.2)
				(max_length 1)
				(best_width_ratio 0.9)
				(max_width 2)
				(curved_edges yes)
				(filter_ratio 0.9)
				(enabled yes)
				(allow_two_segments yes)
				(prefer_zone_connections yes)
			)
		)
		(pad "2" smd roundrect
			(at 0.48 0 180)
			(size 0.59 0.64)
			(layers "B.Cu" "B.Mask" "B.Paste")
			(roundrect_rratio 0.25)
			(net 43 "/2xUSB3.0+RJ45/P2_VBUS")
			(pintype "passive")
			(teardrops
				(best_length_ratio 0.2)
				(max_length 1)
				(best_width_ratio 0.9)
				(max_width 2)
				(curved_edges yes)
				(filter_ratio 0.9)
				(enabled yes)
				(allow_two_segments yes)
				(prefer_zone_connections yes)
			)
		)
	)
	(footprint "antmicro-footprints:TP_SMD_0.75mm"
		(layer "B.Cu")
		(at 141.8 167.21 180)
		(property "Reference" "TP4"
			(at 0.35 0.45 0)
			(layer "B.SilkS")
			(effects
				(font
					(size 0.7 0.7)
					(thickness 0.15)
				)
				(justify left bottom mirror)
			)
		)
		(property "Value" "TP_0.75mm_SMD"
			(at 0 -1.2 0)
			(layer "B.Fab")
			(effects
				(font
					(size 0.7 0.7)
					(thickness 0.15)
				)
				(justify left bottom mirror)
			)
		)
		(property "Author" "Antmicro"
			(at 283.6 334.42 0)
			(layer "B.Fab")
			(hide yes)
			(effects
				(font
					(size 1 1)
					(thickness 0.15)
				)
				(justify mirror)
			)
		)
		(property "License" "Apache-2.0"
			(at 283.6 334.42 0)
			(layer "B.Fab")
			(hide yes)
			(effects
				(font
					(size 1 1)
					(thickness 0.15)
				)
				(justify mirror)
			)
		)
		(property "MPN" ""
			(at 283.6 334.42 0)
			(layer "B.Fab")
			(hide yes)
			(effects
				(font
					(size 1 1)
					(thickness 0.15)
				)
				(justify mirror)
			)
		)
		(property "Manufacturer" ""
			(at 283.6 334.42 0)
			(layer "B.Fab")
			(hide yes)
			(effects
				(font
					(size 1 1)
					(thickness 0.15)
				)
				(justify mirror)
			)
		)
		(property "Public" "False"
			(at 283.6 334.42 0)
			(layer "B.Fab")
			(hide yes)
			(effects
				(font
					(size 1 1)
					(thickness 0.15)
				)
				(justify mirror)
			)
		)
		(sheetname "2xSFP+")
		(sheetfile "2xSFP+.kicad_sch")
		(attr exclude_from_pos_files exclude_from_bom)
		(fp_circle
			(center 0 0)
			(end 0.475 0)
			(stroke
				(width 0.05)
				(type default)
			)
			(fill no)
			(layer "B.CrtYd")
		)
		(pad "1" smd circle
			(at 0 0 180)
			(size 0.75 0.75)
			(layers "B.Cu" "B.Mask")
			(net 876 "Net-(J2B-TX_{FAULT})")
			(pinfunction "1")
			(pintype "passive")
			(teardrops
				(best_length_ratio 0.4)
				(max_length 1)
				(best_width_ratio 0.9)
				(max_width 2)
				(curved_edges yes)
				(filter_ratio 0.9)
				(enabled yes)
				(allow_two_segments yes)
				(prefer_zone_connections yes)
			)
		)
	)
	(footprint "antmicro-footprints:R_0402_1005Metric"
		(layer "B.Cu")
		(at 309.824999 106.15 -90)
		(descr "Resistor SMD 0402")
		(tags "resistor SMD 0402")
		(property "Reference" "R91"
			(at 0.76 -0.475001 90)
			(layer "B.SilkS")
			(effects
				(font
					(size 0.7 0.7)
					(thickness 0.15)
				)
				(justify left bottom mirror)
			)
		)
		(property "Value" "R_68k_0402"
			(at -1.011843 -1.772047 90)
			(layer "B.Fab")
			(effects
				(font
					(size 0.7 0.7)
					(thickness 0.15)
				)
				(justify left bottom mirror)
			)
		)
		(property "Datasheet" "https://www.bourns.com/docs/product-datasheets/cr.pdf"
			(at 0 0 270)
			(layer "F.Fab")
			(hide yes)
			(effects
				(font
					(size 1.27 1.27)
					(thickness 0.15)
				)
			)
		)
		(property "Author" "Antmicro"
			(at 203.674999 415.974999 0)
			(layer "B.Fab")
			(hide yes)
			(effects
				(font
					(size 1 1)
					(thickness 0.15)
				)
				(justify mirror)
			)
		)
		(property "License" "Apache-2.0"
			(at 203.674999 415.974999 0)
			(layer "B.Fab")
			(hide yes)
			(effects
				(font
					(size 1 1)
					(thickness 0.15)
				)
				(justify mirror)
			)
		)
		(property "MPN" "CR0402-FX-6802GLF"
			(at 203.674999 415.974999 0)
			(layer "B.Fab")
			(hide yes)
			(effects
				(font
					(size 1 1)
					(thickness 0.15)
				)
				(justify mirror)
			)
		)
		(property "Manufacturer" "Bourns"
			(at 203.674999 415.974999 0)
			(layer "B.Fab")
			(hide yes)
			(effects
				(font
					(size 1 1)
					(thickness 0.15)
				)
				(justify mirror)
			)
		)
		(property "Public" "False"
			(at 203.674999 415.974999 0)
			(layer "B.Fab")
			(hide yes)
			(effects
				(font
					(size 1 1)
					(thickness 0.15)
				)
				(justify mirror)
			)
		)
		(property "Tolerance" "1%"
			(at 203.674999 415.974999 0)
			(layer "B.Fab")
			(hide yes)
			(effects
				(font
					(size 1 1)
					(thickness 0.15)
				)
				(justify mirror)
			)
		)
		(property "Val" "68k"
			(at 203.674999 415.974999 0)
			(layer "B.Fab")
			(hide yes)
			(effects
				(font
					(size 1 1)
					(thickness 0.15)
				)
				(justify mirror)
			)
		)
		(sheetname "Power")
		(sheetfile "power.kicad_sch")
		(attr smd dnp)
		(fp_rect
			(start -0.925 0.47)
			(end 0.925 -0.47)
			(stroke
				(width 0.05)
				(type default)
			)
			(fill no)
			(layer "B.CrtYd")
		)
		(fp_rect
			(start -0.5 0.25)
			(end 0.5 -0.25)
			(stroke
				(width 0.15)
				(type solid)
			)
			(fill no)
			(layer "B.Fab")
		)
		(pad "1" smd roundrect
			(at -0.48 0 270)
			(size 0.59 0.64)
			(layers "B.Cu" "B.Mask" "B.Paste")
			(roundrect_rratio 0.25)
			(net 576 "Net-(U19-MODE)")
			(pintype "passive")
			(teardrops
				(best_length_ratio 0.2)
				(max_length 1)
				(best_width_ratio 0.9)
				(max_width 2)
				(curved_edges yes)
				(filter_ratio 0.9)
				(enabled yes)
				(allow_two_segments yes)
				(prefer_zone_connections yes)
			)
		)
		(pad "2" smd roundrect
			(at 0.48 0 270)
			(size 0.59 0.64)
			(layers "B.Cu" "B.Mask" "B.Paste")
			(roundrect_rratio 0.25)
			(net 64 "Net-(U19-V_{CC})")
			(pintype "passive")
			(teardrops
				(best_length_ratio 0.2)
				(max_length 1)
				(best_width_ratio 0.9)
				(max_width 2)
				(curved_edges yes)
				(filter_ratio 0.9)
				(enabled yes)
				(allow_two_segments yes)
				(prefer_zone_connections yes)
			)
		)
	)
	(footprint "antmicro-footprints:TP_SMD_0.75mm"
		(layer "B.Cu")
		(at 176.25 166.1)
		(property "Reference" "TP29"
			(at 1 -0.35 180)
			(layer "B.SilkS")
			(effects
				(font
					(size 0.7 0.7)
					(thickness 0.15)
				)
				(justify right top mirror)
			)
		)
		(property "Value" "TP_0.75mm_SMD"
			(at 3.225 -53.865 0)
			(layer "B.Fab")
			(hide yes)
			(effects
				(font
					(size 0.7 0.7)
					(thickness 0.15)
				)
				(justify right top mirror)
			)
		)
		(property "Author" "Antmicro"
			(at 453.6 306.12 0)
			(layer "B.Fab")
			(hide yes)
			(effects
				(font
					(size 1 1)
					(thickness 0.15)
				)
				(justify mirror)
			)
		)
		(property "License" "Apache-2.0"
			(at 453.6 306.12 0)
			(layer "B.Fab")
			(hide yes)
			(effects
				(font
					(size 1 1)
					(thickness 0.15)
				)
				(justify mirror)
			)
		)
		(property "MPN" ""
			(at 453.6 306.12 0)
			(layer "B.Fab")
			(hide yes)
			(effects
				(font
					(size 1 1)
					(thickness 0.15)
				)
				(justify mirror)
			)
		)
		(property "Manufacturer" ""
			(at 453.6 306.12 0)
			(layer "B.Fab")
			(hide yes)
			(effects
				(font
					(size 1 1)
					(thickness 0.15)
				)
				(justify mirror)
			)
		)
		(property "Public" "False"
			(at 453.6 306.12 0)
			(layer "B.Fab")
			(hide yes)
			(effects
				(font
					(size 1 1)
					(thickness 0.15)
				)
				(justify mirror)
			)
		)
		(sheetname "Com Express 7 MGMT")
		(sheetfile "com_express_7_mgmt.kicad_sch")
		(attr exclude_from_pos_files exclude_from_bom)
		(fp_circle
			(center 0 0)
			(end 0.475 0)
			(stroke
				(width 0.05)
				(type default)
			)
			(fill no)
			(layer "B.CrtYd")
		)
		(pad "1" smd circle
			(at 0 0)
			(size 0.75 0.75)
			(layers "B.Cu" "B.Mask")
			(net 353 "Net-(J12D-~{LPC_DRQ0}{slash}~{ESPI_ALERT0})")
			(pinfunction "1")
			(pintype "passive")
			(teardrops
				(best_length_ratio 0.4)
				(max_length 1)
				(best_width_ratio 0.9)
				(max_width 2)
				(curved_edges yes)
				(filter_ratio 0.9)
				(enabled yes)
				(allow_two_segments yes)
				(prefer_zone_connections yes)
			)
		)
	)
)
